(kicad_pcb
	(version 20260206)
	(generator "pcbnew")
	(generator_version "10.0")
	(general
		(thickness 1.6)
		(legacy_teardrops no)
	)
	(paper "A4")
	(title_block
		(title "03242023_DA0F0TMBIJ0_F0T_Motherboard_J_brd_V01_OCP.brd")
		(comment 1 "Grand Teton / footprints 3800-3806 of 6105")
	)
	(layers
		(0 "F.Cu" signal "TOP")
		(4 "In1.Cu" signal "GND")
		(6 "In2.Cu" signal "IN1")
		(8 "In3.Cu" signal "GND1")
		(10 "In4.Cu" signal "IN2")
		(12 "In5.Cu" signal "GND2")
		(14 "In6.Cu" signal "IN3")
		(16 "In7.Cu" signal "GND3")
		(18 "In8.Cu" signal "VCC")
		(20 "In9.Cu" signal "VCC1")
		(22 "In10.Cu" signal "GND4")
		(24 "In11.Cu" signal "IN4")
		(26 "In12.Cu" signal "GND5")
		(28 "In13.Cu" signal "IN5")
		(30 "In14.Cu" signal "GND6")
		(32 "In15.Cu" signal "IN6")
		(34 "In16.Cu" signal "GND7")
		(2 "B.Cu" signal "BOTTOM")
		(9 "F.Adhes" user "F.Adhesive")
		(11 "B.Adhes" user "B.Adhesive")
		(13 "F.Paste" user "Package Geometry/Pastemask Top")
		(15 "B.Paste" user "Package Geometry/Pastemask Bottom")
		(5 "F.SilkS" user "Ref Des/Silkscreen Top")
		(7 "B.SilkS" user "Ref Des/Silkscreen Bottom")
		(1 "F.Mask" user "Board Geometry/Soldermask Top")
		(3 "B.Mask" user "Board Geometry/Soldermask Bottom")
		(17 "Dwgs.User" user "User.Drawings")
		(19 "Cmts.User" user "User.Comments")
		(21 "Eco1.User" user "User.Eco1")
		(23 "Eco2.User" user "User.Eco2")
		(25 "Edge.Cuts" user "Board Geometry/Outline")
		(27 "Margin" user)
		(31 "F.CrtYd" user "Package Geometry/Place Bound Top")
		(29 "B.CrtYd" user "Package Geometry/Place Bound Bottom")
		(35 "F.Fab" user "Ref Des/Assembly Top")
		(33 "B.Fab" user "Ref Des/Assembly Bottom")
	)
	(footprint ""
		(layer "F.Cu")
		(at 180.4924 -94.338648 90)
		(property "Reference" "R4596"
			(at 0 0 90)
			(layer "F.SilkS")
			(hide yes)
			(effects
				(font
					(size 1.27 1.27)
				)
			)
		)
		(property "Value" ""
			(at 0 0 90)
			(layer "F.Fab")
			(effects
				(font
					(size 1.27 1.27)
				)
			)
		)
		(duplicate_pad_numbers_are_jumpers no)
		(fp_line
			(start 0.7874 -0.4064)
			(end 0.7874 0.4064)
			(stroke
				(width 0.1524)
				(type default)
			)
			(layer "F.SilkS")
		)
		(fp_line
			(start -0.7874 -0.4064)
			(end 0.7874 -0.4064)
			(stroke
				(width 0.1524)
				(type default)
			)
			(layer "F.SilkS")
		)
		(fp_line
			(start 0.7874 0.4064)
			(end -0.7874 0.4064)
			(stroke
				(width 0.1524)
				(type default)
			)
			(layer "F.SilkS")
		)
		(fp_line
			(start -0.7874 0.4064)
			(end -0.7874 -0.4064)
			(stroke
				(width 0.1524)
				(type default)
			)
			(layer "F.SilkS")
		)
		(fp_line
			(start -0.12065 -0.305054)
			(end -0.12065 -0.2794)
			(stroke
				(width 0.1)
				(type default)
			)
			(layer "F.Fab")
		)
		(fp_line
			(start -0.67945 -0.305054)
			(end -0.12065 -0.305054)
			(stroke
				(width 0.1)
				(type default)
			)
			(layer "F.Fab")
		)
		(fp_line
			(start 0.67945 -0.3048)
			(end 0.67945 0.3048)
			(stroke
				(width 0.1)
				(type default)
			)
			(layer "F.Fab")
		)
		(fp_line
			(start 0.12065 -0.3048)
			(end 0.67945 -0.3048)
			(stroke
				(width 0.1)
				(type default)
			)
			(layer "F.Fab")
		)
		(fp_line
			(start 0.12065 -0.2794)
			(end 0.12065 -0.3048)
			(stroke
				(width 0.1)
				(type default)
			)
			(layer "F.Fab")
		)
		(fp_line
			(start -0.12065 -0.2794)
			(end 0.12065 -0.2794)
			(stroke
				(width 0.1)
				(type default)
			)
			(layer "F.Fab")
		)
		(fp_line
			(start 0.120396 0.2794)
			(end -0.12065 0.2794)
			(stroke
				(width 0.1)
				(type default)
			)
			(layer "F.Fab")
		)
		(fp_line
			(start -0.12065 0.2794)
			(end -0.12065 0.3048)
			(stroke
				(width 0.1)
				(type default)
			)
			(layer "F.Fab")
		)
		(fp_line
			(start 0.67945 0.3048)
			(end 0.120396 0.3048)
			(stroke
				(width 0.1)
				(type default)
			)
			(layer "F.Fab")
		)
		(fp_line
			(start 0.120396 0.3048)
			(end 0.120396 0.2794)
			(stroke
				(width 0.1)
				(type default)
			)
			(layer "F.Fab")
		)
		(fp_line
			(start -0.12065 0.3048)
			(end -0.67945 0.3048)
			(stroke
				(width 0.1)
				(type default)
			)
			(layer "F.Fab")
		)
		(fp_line
			(start -0.67945 0.3048)
			(end -0.67945 -0.305054)
			(stroke
				(width 0.1)
				(type default)
			)
			(layer "F.Fab")
		)
		(pad "1" smd rect
			(at -0.40005 0 270)
			(size 0.4572 0.508)
			(layers "F.Cu" "F.Mask" "F.Paste")
			(net "FAB_BMC_REV_ID0")
		)
		(pad "2" smd rect
			(at 0.40005 0 270)
			(size 0.4572 0.508)
			(layers "F.Cu" "F.Mask" "F.Paste")
			(net "GND")
		)
	)
	(footprint ""
		(layer "F.Cu")
		(at 352.289618 -244.03177 90)
		(property "Reference" "C995"
			(at 0 0 90)
			(layer "F.SilkS")
			(hide yes)
			(effects
				(font
					(size 1.27 1.27)
				)
			)
		)
		(property "Value" ""
			(at 0 0 90)
			(layer "F.Fab")
			(effects
				(font
					(size 1.27 1.27)
				)
			)
		)
		(duplicate_pad_numbers_are_jumpers no)
		(fp_line
			(start 0.7874 -0.4064)
			(end 0.7874 0.4064)
			(stroke
				(width 0.1524)
				(type default)
			)
			(layer "F.SilkS")
		)
		(fp_line
			(start -0.7874 -0.4064)
			(end 0.7874 -0.4064)
			(stroke
				(width 0.1524)
				(type default)
			)
			(layer "F.SilkS")
		)
		(fp_line
			(start 0.7874 0.4064)
			(end -0.7874 0.4064)
			(stroke
				(width 0.1524)
				(type default)
			)
			(layer "F.SilkS")
		)
		(fp_line
			(start -0.7874 0.4064)
			(end -0.7874 -0.4064)
			(stroke
				(width 0.1524)
				(type default)
			)
			(layer "F.SilkS")
		)
		(fp_line
			(start -0.12065 -0.305054)
			(end -0.12065 -0.2794)
			(stroke
				(width 0.1)
				(type default)
			)
			(layer "F.Fab")
		)
		(fp_line
			(start -0.67945 -0.305054)
			(end -0.12065 -0.305054)
			(stroke
				(width 0.1)
				(type default)
			)
			(layer "F.Fab")
		)
		(fp_line
			(start 0.67945 -0.3048)
			(end 0.67945 0.3048)
			(stroke
				(width 0.1)
				(type default)
			)
			(layer "F.Fab")
		)
		(fp_line
			(start 0.12065 -0.3048)
			(end 0.67945 -0.3048)
			(stroke
				(width 0.1)
				(type default)
			)
			(layer "F.Fab")
		)
		(fp_line
			(start 0.12065 -0.2794)
			(end 0.12065 -0.3048)
			(stroke
				(width 0.1)
				(type default)
			)
			(layer "F.Fab")
		)
		(fp_line
			(start -0.12065 -0.2794)
			(end 0.12065 -0.2794)
			(stroke
				(width 0.1)
				(type default)
			)
			(layer "F.Fab")
		)
		(fp_line
			(start 0.120396 0.2794)
			(end -0.12065 0.2794)
			(stroke
				(width 0.1)
				(type default)
			)
			(layer "F.Fab")
		)
		(fp_line
			(start -0.12065 0.2794)
			(end -0.12065 0.3048)
			(stroke
				(width 0.1)
				(type default)
			)
			(layer "F.Fab")
		)
		(fp_line
			(start 0.67945 0.3048)
			(end 0.120396 0.3048)
			(stroke
				(width 0.1)
				(type default)
			)
			(layer "F.Fab")
		)
		(fp_line
			(start 0.120396 0.3048)
			(end 0.120396 0.2794)
			(stroke
				(width 0.1)
				(type default)
			)
			(layer "F.Fab")
		)
		(fp_line
			(start -0.12065 0.3048)
			(end -0.67945 0.3048)
			(stroke
				(width 0.1)
				(type default)
			)
			(layer "F.Fab")
		)
		(fp_line
			(start -0.67945 0.3048)
			(end -0.67945 -0.305054)
			(stroke
				(width 0.1)
				(type default)
			)
			(layer "F.Fab")
		)
		(pad "1" smd circle
			(at -0.40005 0 90)
			(size 0 0)
			(layers "F.Cu" "F.Mask" "F.Paste")
			(net "PVCCIN_CPU0")
		)
		(pad "2" smd circle
			(at 0.40005 0 90)
			(size 0 0)
			(layers "F.Cu" "F.Mask" "F.Paste")
			(net "GND")
		)
	)
	(footprint ""
		(layer "F.Cu")
		(at 63.11011 -152.052528 180)
		(property "Reference" "PR4247"
			(at 0 0 180)
			(layer "F.SilkS")
			(hide yes)
			(effects
				(font
					(size 1.27 1.27)
				)
			)
		)
		(property "Value" ""
			(at 0 0 180)
			(layer "F.Fab")
			(effects
				(font
					(size 1.27 1.27)
				)
			)
		)
		(duplicate_pad_numbers_are_jumpers no)
		(fp_line
			(start 0.7874 0.4064)
			(end -0.7874 0.4064)
			(stroke
				(width 0.1524)
				(type default)
			)
			(layer "F.SilkS")
		)
		(fp_line
			(start 0.7874 -0.4064)
			(end 0.7874 0.4064)
			(stroke
				(width 0.1524)
				(type default)
			)
			(layer "F.SilkS")
		)
		(fp_line
			(start -0.7874 0.4064)
			(end -0.7874 -0.4064)
			(stroke
				(width 0.1524)
				(type default)
			)
			(layer "F.SilkS")
		)
		(fp_line
			(start -0.7874 -0.4064)
			(end 0.7874 -0.4064)
			(stroke
				(width 0.1524)
				(type default)
			)
			(layer "F.SilkS")
		)
		(fp_line
			(start 0.67945 0.3048)
			(end 0.120396 0.3048)
			(stroke
				(width 0.1)
				(type default)
			)
			(layer "F.Fab")
		)
		(fp_line
			(start 0.67945 -0.3048)
			(end 0.67945 0.3048)
			(stroke
				(width 0.1)
				(type default)
			)
			(layer "F.Fab")
		)
		(fp_line
			(start 0.12065 -0.2794)
			(end 0.12065 -0.3048)
			(stroke
				(width 0.1)
				(type default)
			)
			(layer "F.Fab")
		)
		(fp_line
			(start 0.12065 -0.3048)
			(end 0.67945 -0.3048)
			(stroke
				(width 0.1)
				(type default)
			)
			(layer "F.Fab")
		)
		(fp_line
			(start 0.120396 0.3048)
			(end 0.120396 0.2794)
			(stroke
				(width 0.1)
				(type default)
			)
			(layer "F.Fab")
		)
		(fp_line
			(start 0.120396 0.2794)
			(end -0.12065 0.2794)
			(stroke
				(width 0.1)
				(type default)
			)
			(layer "F.Fab")
		)
		(fp_line
			(start -0.12065 0.3048)
			(end -0.67945 0.3048)
			(stroke
				(width 0.1)
				(type default)
			)
			(layer "F.Fab")
		)
		(fp_line
			(start -0.12065 0.2794)
			(end -0.12065 0.3048)
			(stroke
				(width 0.1)
				(type default)
			)
			(layer "F.Fab")
		)
		(fp_line
			(start -0.12065 -0.2794)
			(end 0.12065 -0.2794)
			(stroke
				(width 0.1)
				(type default)
			)
			(layer "F.Fab")
		)
		(fp_line
			(start -0.12065 -0.305054)
			(end -0.12065 -0.2794)
			(stroke
				(width 0.1)
				(type default)
			)
			(layer "F.Fab")
		)
		(fp_line
			(start -0.67945 0.3048)
			(end -0.67945 -0.305054)
			(stroke
				(width 0.1)
				(type default)
			)
			(layer "F.Fab")
		)
		(fp_line
			(start -0.67945 -0.305054)
			(end -0.12065 -0.305054)
			(stroke
				(width 0.1)
				(type default)
			)
			(layer "F.Fab")
		)
		(pad "1" smd circle
			(at -0.40005 0 180)
			(size 0 0)
			(layers "F.Cu" "F.Mask" "F.Paste")
			(net "PVCCINFAON_CPU1")
		)
		(pad "2" smd circle
			(at 0.40005 0 180)
			(size 0 0)
			(layers "F.Cu" "F.Mask" "F.Paste")
			(net "GND")
		)
	)
	(footprint ""
		(layer "F.Cu")
		(at 239.98809 -47.968408 180)
		(property "Reference" "R3779"
			(at 0 0 180)
			(layer "F.SilkS")
			(hide yes)
			(effects
				(font
					(size 1.27 1.27)
				)
			)
		)
		(property "Value" ""
			(at 0 0 180)
			(layer "F.Fab")
			(effects
				(font
					(size 1.27 1.27)
				)
			)
		)
		(duplicate_pad_numbers_are_jumpers no)
		(fp_line
			(start 0.7874 0.4064)
			(end -0.7874 0.4064)
			(stroke
				(width 0.1524)
				(type default)
			)
			(layer "F.SilkS")
		)
		(fp_line
			(start 0.7874 -0.4064)
			(end 0.7874 0.4064)
			(stroke
				(width 0.1524)
				(type default)
			)
			(layer "F.SilkS")
		)
		(fp_line
			(start -0.7874 0.4064)
			(end -0.7874 -0.4064)
			(stroke
				(width 0.1524)
				(type default)
			)
			(layer "F.SilkS")
		)
		(fp_line
			(start -0.7874 -0.4064)
			(end 0.7874 -0.4064)
			(stroke
				(width 0.1524)
				(type default)
			)
			(layer "F.SilkS")
		)
		(fp_line
			(start 0.67945 0.3048)
			(end 0.120396 0.3048)
			(stroke
				(width 0.1)
				(type default)
			)
			(layer "F.Fab")
		)
		(fp_line
			(start 0.67945 -0.3048)
			(end 0.67945 0.3048)
			(stroke
				(width 0.1)
				(type default)
			)
			(layer "F.Fab")
		)
		(fp_line
			(start 0.12065 -0.2794)
			(end 0.12065 -0.3048)
			(stroke
				(width 0.1)
				(type default)
			)
			(layer "F.Fab")
		)
		(fp_line
			(start 0.12065 -0.3048)
			(end 0.67945 -0.3048)
			(stroke
				(width 0.1)
				(type default)
			)
			(layer "F.Fab")
		)
		(fp_line
			(start 0.120396 0.3048)
			(end 0.120396 0.2794)
			(stroke
				(width 0.1)
				(type default)
			)
			(layer "F.Fab")
		)
		(fp_line
			(start 0.120396 0.2794)
			(end -0.12065 0.2794)
			(stroke
				(width 0.1)
				(type default)
			)
			(layer "F.Fab")
		)
		(fp_line
			(start -0.12065 0.3048)
			(end -0.67945 0.3048)
			(stroke
				(width 0.1)
				(type default)
			)
			(layer "F.Fab")
		)
		(fp_line
			(start -0.12065 0.2794)
			(end -0.12065 0.3048)
			(stroke
				(width 0.1)
				(type default)
			)
			(layer "F.Fab")
		)
		(fp_line
			(start -0.12065 -0.2794)
			(end 0.12065 -0.2794)
			(stroke
				(width 0.1)
				(type default)
			)
			(layer "F.Fab")
		)
		(fp_line
			(start -0.12065 -0.305054)
			(end -0.12065 -0.2794)
			(stroke
				(width 0.1)
				(type default)
			)
			(layer "F.Fab")
		)
		(fp_line
			(start -0.67945 0.3048)
			(end -0.67945 -0.305054)
			(stroke
				(width 0.1)
				(type default)
			)
			(layer "F.Fab")
		)
		(fp_line
			(start -0.67945 -0.305054)
			(end -0.12065 -0.305054)
			(stroke
				(width 0.1)
				(type default)
			)
			(layer "F.Fab")
		)
		(pad "1" smd circle
			(at -0.40005 0 180)
			(size 0 0)
			(layers "F.Cu" "F.Mask" "F.Paste")
			(net "RST_PCIE_PCH_DEV_PERST_E1S_R_N")
		)
		(pad "2" smd circle
			(at 0.40005 0 180)
			(size 0 0)
			(layers "F.Cu" "F.Mask" "F.Paste")
			(net "RST_PCIE_PCH_E1S_PERST_N")
		)
	)
	(footprint ""
		(layer "F.Cu")
		(at 160.83788 -116.296948)
		(property "Reference" "R1467"
			(at 0 0 0)
			(layer "F.SilkS")
			(hide yes)
			(effects
				(font
					(size 1.27 1.27)
				)
			)
		)
		(property "Value" ""
			(at 0 0 0)
			(layer "F.Fab")
			(effects
				(font
					(size 1.27 1.27)
				)
			)
		)
		(duplicate_pad_numbers_are_jumpers no)
		(fp_line
			(start -0.7874 -0.4064)
			(end 0.7874 -0.4064)
			(stroke
				(width 0.1524)
				(type default)
			)
			(layer "F.SilkS")
		)
		(fp_line
			(start -0.7874 0.4064)
			(end -0.7874 -0.4064)
			(stroke
				(width 0.1524)
				(type default)
			)
			(layer "F.SilkS")
		)
		(fp_line
			(start 0.7874 -0.4064)
			(end 0.7874 0.4064)
			(stroke
				(width 0.1524)
				(type default)
			)
			(layer "F.SilkS")
		)
		(fp_line
			(start 0.7874 0.4064)
			(end -0.7874 0.4064)
			(stroke
				(width 0.1524)
				(type default)
			)
			(layer "F.SilkS")
		)
		(fp_line
			(start -0.67945 -0.305054)
			(end -0.12065 -0.305054)
			(stroke
				(width 0.1)
				(type default)
			)
			(layer "F.Fab")
		)
		(fp_line
			(start -0.67945 0.3048)
			(end -0.67945 -0.305054)
			(stroke
				(width 0.1)
				(type default)
			)
			(layer "F.Fab")
		)
		(fp_line
			(start -0.12065 -0.305054)
			(end -0.12065 -0.2794)
			(stroke
				(width 0.1)
				(type default)
			)
			(layer "F.Fab")
		)
		(fp_line
			(start -0.12065 -0.2794)
			(end 0.12065 -0.2794)
			(stroke
				(width 0.1)
				(type default)
			)
			(layer "F.Fab")
		)
		(fp_line
			(start -0.12065 0.2794)
			(end -0.12065 0.3048)
			(stroke
				(width 0.1)
				(type default)
			)
			(layer "F.Fab")
		)
		(fp_line
			(start -0.12065 0.3048)
			(end -0.67945 0.3048)
			(stroke
				(width 0.1)
				(type default)
			)
			(layer "F.Fab")
		)
		(fp_line
			(start 0.120396 0.2794)
			(end -0.12065 0.2794)
			(stroke
				(width 0.1)
				(type default)
			)
			(layer "F.Fab")
		)
		(fp_line
			(start 0.120396 0.3048)
			(end 0.120396 0.2794)
			(stroke
				(width 0.1)
				(type default)
			)
			(layer "F.Fab")
		)
		(fp_line
			(start 0.12065 -0.3048)
			(end 0.67945 -0.3048)
			(stroke
				(width 0.1)
				(type default)
			)
			(layer "F.Fab")
		)
		(fp_line
			(start 0.12065 -0.2794)
			(end 0.12065 -0.3048)
			(stroke
				(width 0.1)
				(type default)
			)
			(layer "F.Fab")
		)
		(fp_line
			(start 0.67945 -0.3048)
			(end 0.67945 0.3048)
			(stroke
				(width 0.1)
				(type default)
			)
			(layer "F.Fab")
		)
		(fp_line
			(start 0.67945 0.3048)
			(end 0.120396 0.3048)
			(stroke
				(width 0.1)
				(type default)
			)
			(layer "F.Fab")
		)
		(pad "1" smd circle
			(at -0.40005 0)
			(size 0 0)
			(layers "F.Cu" "F.Mask" "F.Paste")
			(net "P3V3_AUX")
		)
		(pad "2" smd circle
			(at 0.40005 0)
			(size 0 0)
			(layers "F.Cu" "F.Mask" "F.Paste")
			(net "SMB_1_PLD_3V3AUX_SCL_R1")
		)
	)
	(footprint ""
		(layer "F.Cu")
		(at 115.680236 -355.985826 90)
		(property "Reference" "PJ49"
			(at -1.563878 1.821434 90)
			(unlocked yes)
			(layer "F.SilkS")
			(effects
				(font
					(size 0.7874 0.5842)
					(thickness 0.1524)
				)
				(justify left)
			)
		)
		(property "Value" ""
			(at 0 0 90)
			(layer "F.Fab")
			(effects
				(font
					(size 1.27 1.27)
				)
			)
		)
		(duplicate_pad_numbers_are_jumpers no)
		(pad "1" smd circle
			(at -0.7493 0 180)
			(size 0 0)
			(layers "F.Cu" "F.Mask" "F.Paste")
			(net "VSENSE_PVCCFA_EHV_FIVRA_CPU1_DP")
		)
		(pad "2" smd rect
			(at 0.7493 0)
			(size 0.7112 0.8128)
			(layers "F.Cu" "F.Mask" "F.Paste")
			(net "SH_PVCCFA_EHV_FIVRA_CPU1")
		)
		(zone
			(layer "F.Cu")
			(hatch none 0.5)
			(connect_pads
				(clearance 0)
			)
			(min_thickness 0.25)
			(keepout
				(tracks allowed)
				(vias not_allowed)
				(pads allowed)
				(copperpour not_allowed)
				(footprints allowed)
			)
			(placement
				(enabled no)
				(sheetname "")
			)
			(fill
				(thermal_gap 0.5)
				(thermal_bridge_width 0.5)
				(island_removal_mode 0)
			)
			(polygon
				(pts
					(xy 115.273836 -354.804726) (xy 116.091462 -354.804726) (xy 116.091462 -357.192326) (xy 115.273836 -357.192326)
				)
			)
		)
	)
	(footprint ""
		(layer "F.Cu")
		(at 48.931068 -176.180242)
		(property "Reference" "PC431"
			(at 0 0 0)
			(layer "F.SilkS")
			(hide yes)
			(effects
				(font
					(size 1.27 1.27)
				)
			)
		)
		(property "Value" ""
			(at 0 0 0)
			(layer "F.Fab")
			(effects
				(font
					(size 1.27 1.27)
				)
			)
		)
		(duplicate_pad_numbers_are_jumpers no)
		(fp_line
			(start -0.7874 -0.4064)
			(end 0.7874 -0.4064)
			(stroke
				(width 0.1524)
				(type default)
			)
			(layer "F.SilkS")
		)
		(fp_line
			(start -0.7874 0.4064)
			(end -0.7874 -0.4064)
			(stroke
				(width 0.1524)
				(type default)
			)
			(layer "F.SilkS")
		)
		(fp_line
			(start 0.7874 -0.4064)
			(end 0.7874 0.4064)
			(stroke
				(width 0.1524)
				(type default)
			)
			(layer "F.SilkS")
		)
		(fp_line
			(start 0.7874 0.4064)
			(end -0.7874 0.4064)
			(stroke
				(width 0.1524)
				(type default)
			)
			(layer "F.SilkS")
		)
		(fp_line
			(start -0.67945 -0.305054)
			(end -0.12065 -0.305054)
			(stroke
				(width 0.1)
				(type default)
			)
			(layer "F.Fab")
		)
		(fp_line
			(start -0.67945 0.3048)
			(end -0.67945 -0.305054)
			(stroke
				(width 0.1)
				(type default)
			)
			(layer "F.Fab")
		)
		(fp_line
			(start -0.12065 -0.305054)
			(end -0.12065 -0.2794)
			(stroke
				(width 0.1)
				(type default)
			)
			(layer "F.Fab")
		)
		(fp_line
			(start -0.12065 -0.2794)
			(end 0.12065 -0.2794)
			(stroke
				(width 0.1)
				(type default)
			)
			(layer "F.Fab")
		)
		(fp_line
			(start -0.12065 0.2794)
			(end -0.12065 0.3048)
			(stroke
				(width 0.1)
				(type default)
			)
			(layer "F.Fab")
		)
		(fp_line
			(start -0.12065 0.3048)
			(end -0.67945 0.3048)
			(stroke
				(width 0.1)
				(type default)
			)
			(layer "F.Fab")
		)
		(fp_line
			(start 0.120396 0.2794)
			(end -0.12065 0.2794)
			(stroke
				(width 0.1)
				(type default)
			)
			(layer "F.Fab")
		)
		(fp_line
			(start 0.120396 0.3048)
			(end 0.120396 0.2794)
			(stroke
				(width 0.1)
				(type default)
			)
			(layer "F.Fab")
		)
		(fp_line
			(start 0.12065 -0.3048)
			(end 0.67945 -0.3048)
			(stroke
				(width 0.1)
				(type default)
			)
			(layer "F.Fab")
		)
		(fp_line
			(start 0.12065 -0.2794)
			(end 0.12065 -0.3048)
			(stroke
				(width 0.1)
				(type default)
			)
			(layer "F.Fab")
		)
		(fp_line
			(start 0.67945 -0.3048)
			(end 0.67945 0.3048)
			(stroke
				(width 0.1)
				(type default)
			)
			(layer "F.Fab")
		)
		(fp_line
			(start 0.67945 0.3048)
			(end 0.120396 0.3048)
			(stroke
				(width 0.1)
				(type default)
			)
			(layer "F.Fab")
		)
		(pad "1" smd circle
			(at -0.40005 0)
			(size 0 0)
			(layers "F.Cu" "F.Mask" "F.Paste")
			(net "SW_PVCCFA_EHV_CPU1_BOOT1_R")
		)
		(pad "2" smd circle
			(at 0.40005 0)
			(size 0 0)
			(layers "F.Cu" "F.Mask" "F.Paste")
			(net "SW_PVCCFA_EHV_CPU1_BOOTR1")
		)
	)
)
